# Bryce Canyon_IOM_IOC_Stackup.xlsx — Stack up_16318-2 (pcb-stackup)
|  |  |  |  |  |  | Version |  |  |  |  |  |  |  |  |  |  |  |  |  |  |  |  |  |  |  |  |  |  |  |  |  |  |  |  |  |  |  |  |
| Board Number: |  | 16318-2 |  |  |  | 02 |  |  |  |  |  |  |  |  |  |  |  |  |  |  |  |  |  |  |  |  |  |  |  |  |  |  |  |  |  |  |  |  |
| Project name: |  | Bryce Canyon |  |  |  |  |  |  |  |  |  |  |  |  |  |  |  |  |  |  |  |  |  |  |  |  |  |  |  |  |  |  |  |  |  |  |  |  |
| Model Name: |  | IOM_Broadcom |  |  |  |  |  |  |  |  |  |  |  |  |  |  |  |  |  |  |  |  |  |  |  |  |  |  |  |  |  |  |  |  |  |  |  |  |
| Layer Count: |  | 8 Layer |  |  |  |  |  |  |  |  |  |  |  |  |  |  |  |  |  |  |  |  |  |  |  |  |  |  |  |  |  |  |  |  |  |  |  |  |
| Date: |  | 2017-09-25 00:00:00 |  |  |  |  |  |  |  |  |  |  |  |  |  |  |  |  |  |  |  |  |  |  |  |  |  |  |  |  |  |  |  |  |  |  |  |  |
| Low Loss Material: |  | TU863+VLP (Tg : 180/Td : 370) |  |  |  |  |  |  |  | Single Ended Type(mil) |  |  |  |  | Differential Type(mil) |  |  |  |  |  |  |  |  |  |  |  |  |  |  |  |  |  |  |  |  |  |  |  |
| Gold Finger(Y/N): |  | N |  |  |  |  |  |  | Imp | 50 |  |  |  | Imp | 85 |  |  |  |  |  | 100 |  |  |  |  |  | 97 |  |  |  |  |  | 92 |  |  |  |  |  |
| Customer: |  | <name> |  |  |  |  |  |  | Variation | Inner/Outer+/-5ohm |  |  |  | Variation | Inner/Outer+/-10% |  |  |  |  |  | Inner/Outer+/-10% |  |  |  |  |  | Outer+/-10% |  |  |  |  |  | Outer+/-10% |  |  |  |  |  |
| EE engineer |  | <name> |  |  |  |  |  |  | Bus | MISC./I2C |  |  |  | Bus | PCIe/Clock/USB |  |  |  |  |  | Clock/SATA |  |  |  |  |  | BGA Break out(SAS.SATA) |  |  |  |  |  | BGA Break out(PCIE) |  |  |  |  |  |
| SI Engineer |  | <name> |  |  |  |  |  |  |  |  |  |  |  |  |  |  |  |  |  |  |  |  |  |  |  |  |  |  |  |  |  |  |  |  |  |  |  |  |
|  |  |  |  |  |  |  |  |  | Type | SE |  |  |  | Type | DP |  |  |  |  |  | DP |  |  |  |  |  | DP |  |  |  |  |  | DP |  |  |  |  |  |
| Layer |  |  | Thickness |  | Glass/Copper Style | Er |  | Df(1G) | Layers | 1,3,6,8 |  |  |  | Layers | 1,3,6,8 |  |  |  |  |  | 1,3,6,8 |  |  |  |  |  | 1,8 |  |  |  |  |  | 1,8 |  |  |  |  |  |
|  |  | Cu oz | Wiwynn |  |  | Wiwynn |  |  |  | Wiwynn |  |  |  |  | Wiwynn |  |  |  |  |  | Wiwynn |  |  |  |  |  | Wiwynn |  |  |  |  |  | Wiwynn |  |  |  |  |  |
|  | Mask |  | 0.5 |  |  | 3.4 |  |  |  | Width | Imp | Width | Imp |  | Width | Space | Imp | Width | Space | Imp | Width | Space | Imp | Width | Space | Imp | Width | Space | Imp | Width | Space | Imp | Width | Space | Imp | Width | Space | Imp |
| Top | Signal | 3/8 oz+plating | 1.7 |  |  |  |  |  | S1 | 5(L2) | 50.08 |  |  | S1 | 5.75(L2) | 6.5 | 85.36 |  |  |  | 4.9(L2) | 11.1 | 96.82 |  |  |  | 3.5(L2) | 4 |  |  |  |  | 3.75(L2) | 3.5 |  |  |  |  |
|  | Prepreg |  | 3 |  |  | 3.9 |  |  |  |  |  |  |  |  |  |  |  |  |  |  |  |  |  |  |  |  |  |  |  |  |  |  |  |  |  |  |  |  |
| L2 | GND | 1 oz | 1.3 |  |  |  |  |  | P2 | reference layer |  |  |  | P2 | reference layer |  |  |  |  |  | reference layer |  |  |  |  |  | reference layer |  |  |  |  |  | reference layer |  |  |  |  |  |
|  | Core |  | 4 |  |  | 3.9 |  |  |  |  |  |  |  |  |  |  |  |  |  |  |  |  |  |  |  |  |  |  |  |  |  |  |  |  |  |  |  |  |
| L3 | Signal | 1 oz | 1.3 |  |  |  |  |  | S3 | 5(L2/L4) | 49.28 |  |  | S3 | 5.5(L2/L4) | 7.5 | 84.9 |  |  |  | 4(L2/L4) | 8 | 97.59 |  |  |  |  |  |  |  |  |  |  |  |  |  |  |  |
|  | Prepreg |  | 16.4 |  |  | 4.2 |  |  |  |  |  |  |  |  |  |  |  |  |  |  |  |  |  |  |  |  |  |  |  |  |  |  |  |  |  |  |  |  |
| L4 | POWER | 1 oz | 1.3 |  |  |  |  |  | P4 | reference layer |  |  |  | P4 | reference layer |  |  |  |  |  | reference layer |  |  |  |  |  | reference layer |  |  |  |  |  | reference layer |  |  |  |  |  |
|  | Core |  | 4 |  |  | 3.8 | 0 | 0 |  |  |  |  |  |  |  |  |  |  |  |  |  |  |  |  |  |  |  |  |  |  |  |  |  |  |  |  |  |  |
| L5 | POWER | 1 oz | 1.3 | 0 | 0 |  |  |  | P5 | reference layer |  |  |  | P5 | reference layer |  |  |  |  |  | reference layer |  |  |  |  |  | reference layer |  |  |  |  |  | reference layer |  |  |  |  |  |
|  | Prepreg |  | 16.4 | 0 | 0 | 4.2 | 0 | 0 |  |  |  |  |  |  |  |  |  |  |  |  |  |  |  |  |  |  |  |  |  |  |  |  |  |  |  |  |  |  |
| L6 | Signal | 1 oz | 1.3 | 0 | 0 |  |  |  | S6 | 5(L5/L7) | 49.28 |  |  | S6 | 5.5(L5/L7) | 7.5 | 84.9 |  |  |  | 4(L5/L7) | 8 | 97.59 |  |  |  |  |  |  |  |  |  |  |  |  |  |  |  |
|  | Core |  | 4 | 0 | 0 | 3.9 | 0 | 0 |  |  |  |  |  |  |  |  |  |  |  |  |  |  |  |  |  |  |  |  |  |  |  |  |  |  |  |  |  |  |
| L7 | GND | 1 oz | 1.3 | 0 | 0 |  |  |  | P7 | reference layer |  |  |  | P7 | reference layer |  |  |  |  |  | reference layer |  |  |  |  |  | reference layer |  |  |  |  |  | reference layer |  |  |  |  |  |
|  | Prepreg |  | 3 | 0 | 0 | 3.9 | 0 | 0 |  |  |  |  |  |  |  |  |  |  |  |  |  |  |  |  |  |  |  |  |  |  |  |  |  |  |  |  |  |  |
| Bottom | Signal | 3/8 oz+plating | 1.7 | 0 | 0 |  |  |  | S8 | 5(L7) | 50.08 |  |  | S8 | 5.75(L7) | 6.5 | 85.36 |  |  |  | 4.9(L7) | 11.1 | 96.82 |  |  |  | 3.5(L7) | 4 |  |  |  |  | 3.75(L7) | 3.5 |  |  |  |  |
|  | Mask |  | 0.5 | 0 |  | 3.4 | 0 | 0 |  |  |  |  |  |  |  |  |  |  |  |  |  |  |  |  |  |  |  |  |  |  |  |  |  |  |  |  |  |  |
| Thickness requirement: 1.6 ± 10% mm |  | mil | 62.99999999999999 |  |  |  |  |  |  |  |  |  |  |  |  |  |  |  |  |  |  |  |  |  |  |  |  |  |  |  |  |  |  |  |  |  |  |  |
|  |  | mm | 1.6002032004064006 |  |  |  |  |  |  |  |  |  |  |  |  |  |  |  |  |  |  |  |  |  |  |  |  |  |  |  |  |  |  |  |  |  |  |  |
| Note: | 1. Unit is mil |  |  |  |  |  |  |  |  |  |  |  |  |  |  |  |  |  |  |  |  |  |  |  |  |  |  |  |  |  |  |  |  |  |  |  |  |  |
|  | 2. The total thickness includes trace and solder mask. |  |  |  |  |  |  |  |  |  |  |  |  |  |  |  |  |  |  |  |  |  |  |  |  |  |  |  |  |  |  |  |  |  |  |  |  |  |
|  | 3. Minimum hole copper thickness is 1.0 mil. |  |  |  |  |  |  |  |  |  |  |  |  |  |  |  |  |  |  |  |  |  |  |  |  |  |  |  |  |  |  |  |  |  |  |  |  |  |
|  | 4. Minimum surface copper thickness 1.5 mil. |  |  |  |  |  |  |  |  |  |  |  |  |  |  |  |  |  |  |  |  |  |  |  |  |  |  |  |  |  |  |  |  |  |  |  |  |  |
|  | 5. If there is no controlled impedance line described as the stackup in the gerber file, PCB supplier can ignore this kind of impedance control directly, but need to inform Wiwynn in engineering question(EQ). |  |  |  |  |  |  |  |  |  |  |  |  |  |  |  |  |  |  |  |  |  |  |  |  |  |  |  |  |  |  |  |  |  |  |  |  |  |
|  | 6. PCB test coupon requirement and PCB test note are described in the another sheets. |  |  |  |  |  |  |  |  |  |  |  |  |  |  |  |  |  |  |  |  |  |  |  |  |  |  |  |  |  |  |  |  |  |  |  |  |  |
|  | 7. If there is no "Delta-L" design in gerber file, PCB supplier should design 85 ohm "Delta-L" angle routing coupon and provide the measurement results in FAI report which meet the following criteria: |  |  |  |  |  |  |  |  |  |  |  |  |  |  |  |  |  |  |  |  |  |  |  |  |  |  |  |  |  |  |  |  |  |  |  |  |  |
|  | For low-loss material |  |  |  |  |  |  |  |  |  |  |  |  |  |  |  |  |  |  |  |  |  |  |  |  |  |  |  |  |  |  |  |  |  |  |  |  |  |
|  | (1)   0.55 dB/inch @ 4GHz; 1.05 dB/inch @ 8GHz for microstrip routing |  |  |  |  |  |  |  |  |  |  |  |  |  |  |  |  |  |  |  |  |  |  |  |  |  |  |  |  |  |  |  |  |  |  |  |  |  |
|  | (2)   0.48 dB/inch @ 4GHz; 0.9 dB/inch @ 8GHz for stripline routing |  |  |  |  |  |  |  |  |  |  |  |  |  |  |  |  |  |  |  |  |  |  |  |  |  |  |  |  |  |  |  |  |  |  |  |  |  |
